(kicad_pcb
	(version 20260206)
	(generator "pcbnew")
	(generator_version "10.0")
	(general
		(thickness 1.6)
		(legacy_teardrops no)
	)
	(paper "A4")
	(title_block
		(title "Wiwynn_Tioga_Pass_MB.brd")
		(comment 1 "Tioga Pass / footprint 2254 of 4770 (U5D1), pads 3264-3371 of 3647")
	)
	(layers
		(0 "F.Cu" signal "TOP")
		(4 "In1.Cu" signal "L2GND")
		(6 "In2.Cu" signal "L3")
		(8 "In3.Cu" signal "L4GND")
		(10 "In4.Cu" signal "L5")
		(12 "In5.Cu" signal "L6GND")
		(14 "In6.Cu" signal "L7VCC")
		(16 "In7.Cu" signal "L8VCC")
		(18 "In8.Cu" signal "L9GND")
		(20 "In9.Cu" signal "L10")
		(22 "In10.Cu" signal "L11GND")
		(24 "In11.Cu" signal "L12")
		(26 "In12.Cu" signal "L13GND")
		(2 "B.Cu" signal "BOTTOM")
		(9 "F.Adhes" user "F.Adhesive")
		(11 "B.Adhes" user "B.Adhesive")
		(13 "F.Paste" user "Package Geometry/Pastemask Top")
		(15 "B.Paste" user "Package Geometry/Pastemask Bottom")
		(5 "F.SilkS" user "Ref Des/Silkscreen Top")
		(7 "B.SilkS" user "Ref Des/Silkscreen Bottom")
		(1 "F.Mask" user "Board Geometry/Soldermask Top")
		(3 "B.Mask" user "Board Geometry/Soldermask Bottom")
		(17 "Dwgs.User" user "User.Drawings")
		(19 "Cmts.User" user "User.Comments")
		(21 "Eco1.User" user "User.Eco1")
		(23 "Eco2.User" user "User.Eco2")
		(25 "Edge.Cuts" user "Board Geometry/Outline")
		(27 "Margin" user)
		(31 "F.CrtYd" user "Package Geometry/Place Bound Top")
		(29 "B.CrtYd" user "Package Geometry/Place Bound Bottom")
		(35 "F.Fab" user "Ref Des/Assembly Top")
		(33 "B.Fab" user "Ref Des/Assembly Bottom")
	)
	(footprint ""
		(layer "F.Cu")
		(at 270.000222 -76.550012 180)
		(property "Reference" "U5D1"
			(at 19.124422 31.601918 0)
			(unlocked yes)
			(layer "F.SilkS")
			(effects
				(font
					(size 0.7874 0.5842)
					(thickness 0.1524)
				)
			)
		)
		(property "Value" ""
			(at 0 0 180)
			(layer "F.Fab")
			(effects
				(font
					(size 1.27 1.27)
				)
			)
		)
		(duplicate_pad_numbers_are_jumpers no)
		(pad "L86" smd custom
			(at 37.250624 -21.950172 270)
			(size 0.10795 0.10795)
			(layers "F.Cu" "F.Mask" "F.Paste")
			(net "M_A_DQ<10>")
			(options
				(clearance outline)
				(anchor circle)
			)
			(primitives
				(gr_poly
					(pts
						(arc
							(start 0.2159 -0.0381)
							(mid 0 -0.254)
							(end -0.2159 -0.0381)
						)
						(arc
							(start -0.2159 0.0381)
							(mid 0 0.254)
							(end 0.2159 0.0381)
						)
					)
					(width 0)
					(fill yes)
				)
			)
		)
		(pad "M1" smd custom
			(at -37.250624 -19.655028 90)
			(size 0.10795 0.10795)
			(layers "F.Cu" "F.Mask" "F.Paste")
			(net "UPI_CPU0_CPU1_P0P0_DP<19>")
			(options
				(clearance outline)
				(anchor circle)
			)
			(primitives
				(gr_poly
					(pts
						(arc
							(start 0.2159 -0.0381)
							(mid 0 -0.254)
							(end -0.2159 -0.0381)
						)
						(arc
							(start -0.2159 0.0381)
							(mid 0 0.254)
							(end 0.2159 0.0381)
						)
					)
					(width 0)
					(fill yes)
				)
			)
		)
		(pad "M3" smd circle
			(at -35.533584 -19.655028)
			(size 0.4318 0.4318)
			(layers "F.Cu" "F.Mask" "F.Paste")
			(net "UPI_CPU0_CPU1_P1P1_DN<19>")
		)
		(pad "M5" smd circle
			(at -33.816544 -19.655028)
			(size 0.4318 0.4318)
			(layers "F.Cu" "F.Mask" "F.Paste")
			(net "UPI_CPU0_CPU1_P1P1_DP<17>")
		)
		(pad "M7" smd circle
			(at -32.099504 -19.655028)
			(size 0.4318 0.4318)
			(layers "F.Cu" "F.Mask" "F.Paste")
			(net "PVCCIO_CPU0")
		)
		(pad "M9" smd circle
			(at -30.382464 -19.655028)
			(size 0.4318 0.4318)
			(layers "F.Cu" "F.Mask" "F.Paste")
			(net "PVCCIO_CPU0")
		)
		(pad "M11" smd circle
			(at -28.665424 -19.655028)
			(size 0.4318 0.4318)
			(layers "F.Cu" "F.Mask" "F.Paste")
			(net "PVCCIO_CPU0")
		)
		(pad "M13" smd circle
			(at -26.948384 -19.655028)
			(size 0.4318 0.4318)
			(layers "F.Cu" "F.Mask" "F.Paste")
			(net "UPI_CPU1_CPU0_P1P1_DP<11>")
		)
		(pad "M15" smd circle
			(at -25.231598 -19.655028)
			(size 0.4318 0.4318)
			(layers "F.Cu" "F.Mask" "F.Paste")
			(net "GND")
		)
		(pad "M17" smd circle
			(at -23.514558 -19.655028)
			(size 0.4318 0.4318)
			(layers "F.Cu" "F.Mask" "F.Paste")
			(net "GND")
		)
		(pad "M19" smd circle
			(at -21.797518 -19.655028)
			(size 0.4318 0.4318)
			(layers "F.Cu" "F.Mask" "F.Paste")
			(net "GND")
		)
		(pad "M21" smd circle
			(at -20.080478 -19.655028)
			(size 0.4318 0.4318)
			(layers "F.Cu" "F.Mask" "F.Paste")
			(net "PVCCIO_CPU0")
		)
		(pad "M23" smd circle
			(at -18.363438 -19.655028)
			(size 0.4318 0.4318)
			(layers "F.Cu" "F.Mask" "F.Paste")
			(net "GND")
		)
		(pad "M25" smd circle
			(at -16.646398 -19.655028)
			(size 0.4318 0.4318)
			(layers "F.Cu" "F.Mask" "F.Paste")
			(net "GND")
		)
		(pad "M27" smd circle
			(at -14.929612 -19.655028)
			(size 0.4318 0.4318)
			(layers "F.Cu" "F.Mask" "F.Paste")
			(net "GND")
		)
		(pad "M29" smd circle
			(at -13.212572 -19.655028)
			(size 0.4318 0.4318)
			(layers "F.Cu" "F.Mask" "F.Paste")
			(net "GND")
		)
		(pad "M31" smd circle
			(at -11.495532 -19.655028)
			(size 0.4318 0.4318)
			(layers "F.Cu" "F.Mask" "F.Paste")
			(net "GND")
		)
		(pad "M33" smd circle
			(at -9.778492 -19.655028)
			(size 0.4318 0.4318)
			(layers "F.Cu" "F.Mask" "F.Paste")
			(net "GND")
		)
		(pad "M35" smd circle
			(at -8.061452 -19.655028)
			(size 0.4318 0.4318)
			(layers "F.Cu" "F.Mask" "F.Paste")
			(net "GND")
		)
		(pad "M37" smd circle
			(at -6.344412 -19.655028)
			(size 0.4318 0.4318)
			(layers "F.Cu" "F.Mask" "F.Paste")
			(net "GND")
		)
		(pad "M39" smd circle
			(at -4.627626 -19.655028)
			(size 0.4318 0.4318)
			(layers "F.Cu" "F.Mask" "F.Paste")
			(net "GND")
		)
		(pad "M41" smd circle
			(at -2.910586 -19.655028)
			(size 0.4318 0.4318)
			(layers "F.Cu" "F.Mask" "F.Paste")
			(net "GND")
		)
		(pad "M43" smd circle
			(at -1.193546 -19.655028)
			(size 0.4318 0.4318)
			(layers "F.Cu" "F.Mask" "F.Paste")
			(net "GND")
		)
		(pad "M45" smd circle
			(at 2.052066 -21.455126)
			(size 0.508 0.508)
			(layers "F.Cu" "F.Mask" "F.Paste")
			(net "M_B_CS_N<6>")
		)
		(pad "M47" smd circle
			(at 3.769106 -21.455126)
			(size 0.4318 0.4318)
			(layers "F.Cu" "F.Mask" "F.Paste")
			(net "M_B_C<2>")
		)
		(pad "M49" smd circle
			(at 5.485892 -21.455126)
			(size 0.4318 0.4318)
			(layers "F.Cu" "F.Mask" "F.Paste")
			(net "M_B_ODT<2>")
		)
		(pad "M51" smd circle
			(at 7.202932 -21.455126)
			(size 0.4318 0.4318)
			(layers "F.Cu" "F.Mask" "F.Paste")
			(net "M_B_MA<13>")
		)
		(pad "M53" smd circle
			(at 8.919972 -21.455126)
			(size 0.4318 0.4318)
			(layers "F.Cu" "F.Mask" "F.Paste")
			(net "M_B_CLK_DN<0>")
		)
		(pad "M55" smd circle
			(at 10.637012 -21.455126)
			(size 0.4318 0.4318)
			(layers "F.Cu" "F.Mask" "F.Paste")
			(net "M_B_MA<10>")
		)
		(pad "M57" smd circle
			(at 12.354052 -21.455126)
			(size 0.4318 0.4318)
			(layers "F.Cu" "F.Mask" "F.Paste")
			(net "M_B_CLK_DP<2>")
		)
		(pad "M59" smd circle
			(at 14.071092 -21.455126)
			(size 0.4318 0.4318)
			(layers "F.Cu" "F.Mask" "F.Paste")
			(net "M_B_MA<4>")
		)
		(pad "M61" smd circle
			(at 15.787878 -21.455126)
			(size 0.4318 0.4318)
			(layers "F.Cu" "F.Mask" "F.Paste")
			(net "M_B_BG<0>")
		)
		(pad "M63" smd circle
			(at 17.504918 -21.455126)
			(size 0.4318 0.4318)
			(layers "F.Cu" "F.Mask" "F.Paste")
			(net "TP_CPU0_RSVD_266")
		)
		(pad "M65" smd circle
			(at 19.221958 -21.455126)
			(size 0.4318 0.4318)
			(layers "F.Cu" "F.Mask" "F.Paste")
			(net "GND")
		)
		(pad "M67" smd circle
			(at 20.938998 -21.455126)
			(size 0.4318 0.4318)
			(layers "F.Cu" "F.Mask" "F.Paste")
			(net "M_B_ECC<7>")
		)
		(pad "M69" smd circle
			(at 22.656038 -21.455126)
			(size 0.4318 0.4318)
			(layers "F.Cu" "F.Mask" "F.Paste")
			(net "M_B_ECC<5>")
		)
		(pad "M71" smd circle
			(at 24.373078 -21.455126)
			(size 0.4318 0.4318)
			(layers "F.Cu" "F.Mask" "F.Paste")
			(net "GND")
		)
		(pad "M73" smd circle
			(at 26.090118 -21.455126)
			(size 0.4318 0.4318)
			(layers "F.Cu" "F.Mask" "F.Paste")
			(net "M_A_DQ<26>")
		)
		(pad "M75" smd circle
			(at 27.806904 -21.455126)
			(size 0.4318 0.4318)
			(layers "F.Cu" "F.Mask" "F.Paste")
			(net "M_A_DQS_DP<12>")
		)
		(pad "M77" smd circle
			(at 29.523944 -21.455126)
			(size 0.4318 0.4318)
			(layers "F.Cu" "F.Mask" "F.Paste")
			(net "M_A_DQ<28>")
		)
		(pad "M79" smd circle
			(at 31.240984 -21.455126)
			(size 0.4318 0.4318)
			(layers "F.Cu" "F.Mask" "F.Paste")
			(net "GND")
		)
		(pad "M81" smd circle
			(at 32.958024 -21.455126)
			(size 0.4318 0.4318)
			(layers "F.Cu" "F.Mask" "F.Paste")
			(net "M_A_DQ<19>")
		)
		(pad "M83" smd circle
			(at 34.675064 -21.455126)
			(size 0.4318 0.4318)
			(layers "F.Cu" "F.Mask" "F.Paste")
			(net "GND")
		)
		(pad "M85" smd circle
			(at 36.392104 -21.455126)
			(size 0.4318 0.4318)
			(layers "F.Cu" "F.Mask" "F.Paste")
			(net "GND")
		)
		(pad "N2" smd circle
			(at -36.392104 -19.159474)
			(size 0.4318 0.4318)
			(layers "F.Cu" "F.Mask" "F.Paste")
			(net "UPI_CPU0_CPU1_P0P0_DN<19>")
		)
		(pad "N4" smd circle
			(at -34.675064 -19.159474)
			(size 0.4318 0.4318)
			(layers "F.Cu" "F.Mask" "F.Paste")
			(net "GND")
		)
		(pad "N6" smd circle
			(at -32.958024 -19.159474)
			(size 0.4318 0.4318)
			(layers "F.Cu" "F.Mask" "F.Paste")
			(net "GND")
		)
		(pad "N8" smd circle
			(at -31.240984 -19.159474)
			(size 0.4318 0.4318)
			(layers "F.Cu" "F.Mask" "F.Paste")
			(net "GND")
		)
		(pad "N10" smd circle
			(at -29.523944 -19.159474)
			(size 0.4318 0.4318)
			(layers "F.Cu" "F.Mask" "F.Paste")
			(net "UPI_CPU1_CPU0_P1P1_DP<15>")
		)
		(pad "N12" smd circle
			(at -27.806904 -19.159474)
			(size 0.4318 0.4318)
			(layers "F.Cu" "F.Mask" "F.Paste")
			(net "UPI_CPU1_CPU0_P1P1_DP<12>")
		)
		(pad "N14" smd circle
			(at -26.090118 -19.159474)
			(size 0.4318 0.4318)
			(layers "F.Cu" "F.Mask" "F.Paste")
			(net "UPI_CPU1_CPU0_P1P1_DN<11>")
		)
		(pad "N16" smd circle
			(at -24.373078 -19.159474)
			(size 0.4318 0.4318)
			(layers "F.Cu" "F.Mask" "F.Paste")
			(net "UPI_CPU1_CPU0_P1P1_DP<8>")
		)
		(pad "N18" smd circle
			(at -22.656038 -19.159474)
			(size 0.4318 0.4318)
			(layers "F.Cu" "F.Mask" "F.Paste")
			(net "PVCCIO_CPU0")
		)
		(pad "N20" smd circle
			(at -20.938998 -19.159474)
			(size 0.4318 0.4318)
			(layers "F.Cu" "F.Mask" "F.Paste")
			(net "GND")
		)
		(pad "N22" smd circle
			(at -19.221958 -19.159474)
			(size 0.4318 0.4318)
			(layers "F.Cu" "F.Mask" "F.Paste")
			(net "GND")
		)
		(pad "N24" smd circle
			(at -17.504918 -19.159474)
			(size 0.4318 0.4318)
			(layers "F.Cu" "F.Mask" "F.Paste")
			(net "M_A_DQS_DN<7>")
		)
		(pad "N26" smd circle
			(at -15.787878 -19.159474)
			(size 0.4318 0.4318)
			(layers "F.Cu" "F.Mask" "F.Paste")
			(net "M_A_DQ<61>")
		)
		(pad "N28" smd circle
			(at -14.071092 -19.159474)
			(size 0.4318 0.4318)
			(layers "F.Cu" "F.Mask" "F.Paste")
			(net "M_A_DQ<51>")
		)
		(pad "N30" smd circle
			(at -12.354052 -19.159474)
			(size 0.4318 0.4318)
			(layers "F.Cu" "F.Mask" "F.Paste")
			(net "M_A_DQS_DP<6>")
		)
		(pad "N32" smd circle
			(at -10.637012 -19.159474)
			(size 0.4318 0.4318)
			(layers "F.Cu" "F.Mask" "F.Paste")
			(net "M_A_DQ<53>")
		)
		(pad "N34" smd circle
			(at -8.919972 -19.159474)
			(size 0.4318 0.4318)
			(layers "F.Cu" "F.Mask" "F.Paste")
			(net "M_A_DQ<43>")
		)
		(pad "N36" smd circle
			(at -7.202932 -19.159474)
			(size 0.4318 0.4318)
			(layers "F.Cu" "F.Mask" "F.Paste")
			(net "M_A_DQS_DP<5>")
		)
		(pad "N38" smd circle
			(at -5.485892 -19.159474)
			(size 0.4318 0.4318)
			(layers "F.Cu" "F.Mask" "F.Paste")
			(net "M_A_DQ<45>")
		)
		(pad "N40" smd circle
			(at -3.769106 -19.159474)
			(size 0.4318 0.4318)
			(layers "F.Cu" "F.Mask" "F.Paste")
			(net "M_B_DQ<35>")
		)
		(pad "N42" smd circle
			(at -2.052066 -19.159474)
			(size 0.4318 0.4318)
			(layers "F.Cu" "F.Mask" "F.Paste")
			(net "M_B_DQS_DN<4>")
		)
		(pad "N46" smd circle
			(at 2.910586 -20.959572)
			(size 0.4318 0.4318)
			(layers "F.Cu" "F.Mask" "F.Paste")
			(net "M_B_CS_N<2>")
		)
		(pad "N48" smd circle
			(at 4.627626 -20.959572)
			(size 0.4318 0.4318)
			(layers "F.Cu" "F.Mask" "F.Paste")
			(net "M_B_MA<17>")
		)
		(pad "N50" smd circle
			(at 6.344412 -20.959572)
			(size 0.4318 0.4318)
			(layers "F.Cu" "F.Mask" "F.Paste")
			(net "M_B_ODT<0>")
		)
		(pad "N52" smd circle
			(at 8.061452 -20.959572)
			(size 0.4318 0.4318)
			(layers "F.Cu" "F.Mask" "F.Paste")
			(net "M_B_MA<15>")
		)
		(pad "N54" smd circle
			(at 9.778492 -20.959572)
			(size 0.4318 0.4318)
			(layers "F.Cu" "F.Mask" "F.Paste")
			(net "M_B_CLK_DP<0>")
		)
		(pad "N56" smd circle
			(at 11.495532 -20.959572)
			(size 0.4318 0.4318)
			(layers "F.Cu" "F.Mask" "F.Paste")
			(net "M_B_CLK_DN<2>")
		)
		(pad "N58" smd circle
			(at 13.212572 -20.959572)
			(size 0.4318 0.4318)
			(layers "F.Cu" "F.Mask" "F.Paste")
			(net "M_B_MA<3>")
		)
		(pad "N60" smd circle
			(at 14.929612 -20.959572)
			(size 0.4318 0.4318)
			(layers "F.Cu" "F.Mask" "F.Paste")
			(net "M_B_BG<1>")
		)
		(pad "N62" smd circle
			(at 16.646398 -20.959572)
			(size 0.4318 0.4318)
			(layers "F.Cu" "F.Mask" "F.Paste")
			(net "M_B_CKE<0>")
		)
		(pad "N64" smd circle
			(at 18.363438 -20.959572)
			(size 0.4318 0.4318)
			(layers "F.Cu" "F.Mask" "F.Paste")
			(net "PVDDQ_ABC")
		)
		(pad "N66" smd circle
			(at 20.080478 -20.959572)
			(size 0.4318 0.4318)
			(layers "F.Cu" "F.Mask" "F.Paste")
			(net "GND")
		)
		(pad "N68" smd circle
			(at 21.797518 -20.959572)
			(size 0.4318 0.4318)
			(layers "F.Cu" "F.Mask" "F.Paste")
			(net "M_B_DQS_DN<8>")
		)
		(pad "N70" smd circle
			(at 23.514558 -20.959572)
			(size 0.4318 0.4318)
			(layers "F.Cu" "F.Mask" "F.Paste")
			(net "GND")
		)
		(pad "N72" smd circle
			(at 25.231598 -20.959572)
			(size 0.4318 0.4318)
			(layers "F.Cu" "F.Mask" "F.Paste")
			(net "GND")
		)
		(pad "N74" smd circle
			(at 26.948384 -20.959572)
			(size 0.4318 0.4318)
			(layers "F.Cu" "F.Mask" "F.Paste")
			(net "GND")
		)
		(pad "N76" smd circle
			(at 28.665424 -20.959572)
			(size 0.4318 0.4318)
			(layers "F.Cu" "F.Mask" "F.Paste")
			(net "GND")
		)
		(pad "N78" smd circle
			(at 30.382464 -20.959572)
			(size 0.4318 0.4318)
			(layers "F.Cu" "F.Mask" "F.Paste")
			(net "GND")
		)
		(pad "N80" smd circle
			(at 32.099504 -20.959572)
			(size 0.4318 0.4318)
			(layers "F.Cu" "F.Mask" "F.Paste")
			(net "M_A_DQ<23>")
		)
		(pad "N82" smd circle
			(at 33.816544 -20.959572)
			(size 0.4318 0.4318)
			(layers "F.Cu" "F.Mask" "F.Paste")
			(net "M_A_DQ<18>")
		)
		(pad "N84" smd circle
			(at 35.533584 -20.959572)
			(size 0.4318 0.4318)
			(layers "F.Cu" "F.Mask" "F.Paste")
			(net "M_A_DQ<15>")
		)
		(pad "N86" smd custom
			(at 37.250624 -20.959572 270)
			(size 0.10795 0.10795)
			(layers "F.Cu" "F.Mask" "F.Paste")
			(net "M_A_DQ<14>")
			(options
				(clearance outline)
				(anchor circle)
			)
			(primitives
				(gr_poly
					(pts
						(arc
							(start 0.2159 -0.0381)
							(mid 0 -0.254)
							(end -0.2159 -0.0381)
						)
						(arc
							(start -0.2159 0.0381)
							(mid 0 0.254)
							(end 0.2159 0.0381)
						)
					)
					(width 0)
					(fill yes)
				)
			)
		)
		(pad "P1" smd custom
			(at -37.250624 -18.664428 90)
			(size 0.10795 0.10795)
			(layers "F.Cu" "F.Mask" "F.Paste")
			(net "UPI_CPU0_CPU1_P0P0_DN<18>")
			(options
				(clearance outline)
				(anchor circle)
			)
			(primitives
				(gr_poly
					(pts
						(arc
							(start 0.2159 -0.0381)
							(mid 0 -0.254)
							(end -0.2159 -0.0381)
						)
						(arc
							(start -0.2159 0.0381)
							(mid 0 0.254)
							(end 0.2159 0.0381)
						)
					)
					(width 0)
					(fill yes)
				)
			)
		)
		(pad "P3" smd circle
			(at -35.533584 -18.664428)
			(size 0.4318 0.4318)
			(layers "F.Cu" "F.Mask" "F.Paste")
			(net "UPI_CPU0_CPU1_P1P1_DP<19>")
		)
		(pad "P5" smd circle
			(at -33.816544 -18.664428)
			(size 0.4318 0.4318)
			(layers "F.Cu" "F.Mask" "F.Paste")
			(net "PVCCIO_CPU0")
		)
		(pad "P7" smd circle
			(at -32.099504 -18.664428)
			(size 0.4318 0.4318)
			(layers "F.Cu" "F.Mask" "F.Paste")
			(net "UPI_CPU1_CPU0_P1P1_DN<18>")
		)
		(pad "P9" smd circle
			(at -30.382464 -18.664428)
			(size 0.4318 0.4318)
			(layers "F.Cu" "F.Mask" "F.Paste")
			(net "UPI_CPU1_CPU0_P1P1_DN<15>")
		)
		(pad "P11" smd circle
			(at -28.665424 -18.664428)
			(size 0.4318 0.4318)
			(layers "F.Cu" "F.Mask" "F.Paste")
			(net "GND")
		)
		(pad "P13" smd circle
			(at -26.948384 -18.664428)
			(size 0.4318 0.4318)
			(layers "F.Cu" "F.Mask" "F.Paste")
			(net "UPI_CPU1_CPU0_P1P1_DP<10>")
		)
		(pad "P15" smd circle
			(at -25.231598 -18.664428)
			(size 0.4318 0.4318)
			(layers "F.Cu" "F.Mask" "F.Paste")
			(net "GND")
		)
		(pad "P17" smd circle
			(at -23.514558 -18.664428)
			(size 0.4318 0.4318)
			(layers "F.Cu" "F.Mask" "F.Paste")
			(net "UPI_CPU1_CPU0_P1P1_DN<8>")
		)
		(pad "P19" smd circle
			(at -21.797518 -18.664428)
			(size 0.4318 0.4318)
			(layers "F.Cu" "F.Mask" "F.Paste")
			(net "UPI_CPU1_CPU0_P1P1_DP<5>")
		)
		(pad "P21" smd circle
			(at -20.080478 -18.664428)
			(size 0.4318 0.4318)
			(layers "F.Cu" "F.Mask" "F.Paste")
			(net "UPI_CPU1_CPU0_P1P1_DN<3>")
		)
		(pad "P23" smd circle
			(at -18.363438 -18.664428)
			(size 0.4318 0.4318)
			(layers "F.Cu" "F.Mask" "F.Paste")
			(net "M_A_DQ<58>")
		)
		(pad "P25" smd circle
			(at -16.646398 -18.664428)
			(size 0.4318 0.4318)
			(layers "F.Cu" "F.Mask" "F.Paste")
			(net "M_A_DQ<57>")
		)
		(pad "P27" smd circle
			(at -14.929612 -18.664428)
			(size 0.4318 0.4318)
			(layers "F.Cu" "F.Mask" "F.Paste")
			(net "GND")
		)
		(pad "P29" smd circle
			(at -13.212572 -18.664428)
			(size 0.4318 0.4318)
			(layers "F.Cu" "F.Mask" "F.Paste")
			(net "M_A_DQ<55>")
		)
		(pad "P31" smd circle
			(at -11.495532 -18.664428)
			(size 0.4318 0.4318)
			(layers "F.Cu" "F.Mask" "F.Paste")
			(net "M_A_DQ<49>")
		)
		(pad "P33" smd circle
			(at -9.778492 -18.664428)
			(size 0.4318 0.4318)
			(layers "F.Cu" "F.Mask" "F.Paste")
			(net "GND")
		)
		(pad "P35" smd circle
			(at -8.061452 -18.664428)
			(size 0.4318 0.4318)
			(layers "F.Cu" "F.Mask" "F.Paste")
			(net "M_A_DQ<47>")
		)
		(pad "P37" smd circle
			(at -6.344412 -18.664428)
			(size 0.4318 0.4318)
			(layers "F.Cu" "F.Mask" "F.Paste")
			(net "M_A_DQ<41>")
		)
		(pad "P39" smd circle
			(at -4.627626 -18.664428)
			(size 0.4318 0.4318)
			(layers "F.Cu" "F.Mask" "F.Paste")
			(net "GND")
		)
		(pad "P41" smd circle
			(at -2.910586 -18.664428)
			(size 0.4318 0.4318)
			(layers "F.Cu" "F.Mask" "F.Paste")
			(net "M_B_DQ<39>")
		)
		(pad "P43" smd circle
			(at -1.193546 -18.664428)
			(size 0.4318 0.4318)
			(layers "F.Cu" "F.Mask" "F.Paste")
			(net "M_B_DQ<36>")
		)
	)
)
